(kicad_pcb
	(version 20260206)
	(generator "pcbnew")
	(generator_version "10.0")
	(general
		(thickness 1.6)
		(legacy_teardrops no)
	)
	(paper "A4")
	(title_block
		(title "Wiwynn_Tioga_Pass_MB.brd")
		(comment 1 "Tioga Pass / footprints 3645-3651 of 4770")
	)
	(layers
		(0 "F.Cu" signal "TOP")
		(4 "In1.Cu" signal "L2GND")
		(6 "In2.Cu" signal "L3")
		(8 "In3.Cu" signal "L4GND")
		(10 "In4.Cu" signal "L5")
		(12 "In5.Cu" signal "L6GND")
		(14 "In6.Cu" signal "L7VCC")
		(16 "In7.Cu" signal "L8VCC")
		(18 "In8.Cu" signal "L9GND")
		(20 "In9.Cu" signal "L10")
		(22 "In10.Cu" signal "L11GND")
		(24 "In11.Cu" signal "L12")
		(26 "In12.Cu" signal "L13GND")
		(2 "B.Cu" signal "BOTTOM")
		(9 "F.Adhes" user "F.Adhesive")
		(11 "B.Adhes" user "B.Adhesive")
		(13 "F.Paste" user "Package Geometry/Pastemask Top")
		(15 "B.Paste" user "Package Geometry/Pastemask Bottom")
		(5 "F.SilkS" user "Ref Des/Silkscreen Top")
		(7 "B.SilkS" user "Ref Des/Silkscreen Bottom")
		(1 "F.Mask" user "Board Geometry/Soldermask Top")
		(3 "B.Mask" user "Board Geometry/Soldermask Bottom")
		(17 "Dwgs.User" user "User.Drawings")
		(19 "Cmts.User" user "User.Comments")
		(21 "Eco1.User" user "User.Eco1")
		(23 "Eco2.User" user "User.Eco2")
		(25 "Edge.Cuts" user "Board Geometry/Outline")
		(27 "Margin" user)
		(31 "F.CrtYd" user "Package Geometry/Place Bound Top")
		(29 "B.CrtYd" user "Package Geometry/Place Bound Bottom")
		(35 "F.Fab" user "Ref Des/Assembly Top")
		(33 "B.Fab" user "Ref Des/Assembly Bottom")
	)
	(footprint ""
		(layer "B.Cu")
		(at 400.351498 -34.782506)
		(property "Reference" "R25W93"
			(at -1.01473 0.656336 90)
			(unlocked yes)
			(layer "B.SilkS")
			(effects
				(font
					(size 0.4064 0.254)
					(thickness 0.1524)
				)
				(justify mirror)
			)
		)
		(property "Value" ""
			(at 0 0 0)
			(layer "B.Fab")
			(effects
				(font
					(size 1.27 1.27)
				)
				(justify mirror)
			)
		)
		(duplicate_pad_numbers_are_jumpers no)
		(fp_poly
			(pts
				(xy 0.4953 -0.2032) (xy -0.4953 -0.2032) (xy -0.4953 1.6002) (xy 0.4953 1.6002)
			)
			(stroke
				(width 0)
				(type default)
			)
			(fill no)
			(layer "B.CrtYd")
		)
		(fp_line
			(start -0.4953 -0.2032)
			(end -0.4953 1.6002)
			(stroke
				(width 0.1)
				(type default)
			)
			(layer "B.Fab")
		)
		(fp_line
			(start -0.4953 1.6002)
			(end 0.4953 1.6002)
			(stroke
				(width 0.1)
				(type default)
			)
			(layer "B.Fab")
		)
		(fp_line
			(start 0.4953 -0.2032)
			(end -0.4953 -0.2032)
			(stroke
				(width 0.1)
				(type default)
			)
			(layer "B.Fab")
		)
		(fp_line
			(start 0.4953 1.6002)
			(end 0.4953 -0.2032)
			(stroke
				(width 0.1)
				(type default)
			)
			(layer "B.Fab")
		)
		(pad "1" smd rect
			(at 0 0 180)
			(size 0.762 0.889)
			(layers "B.Cu" "B.Mask" "B.Paste")
			(net "P3V3_STBY")
		)
		(pad "2" smd rect
			(at 0 1.397 180)
			(size 0.762 0.889)
			(layers "B.Cu" "B.Mask" "B.Paste")
			(net "VCC_DACAV3V3")
		)
		(zone
			(layer "B.Cu")
			(hatch none 0.5)
			(connect_pads
				(clearance 0)
			)
			(min_thickness 0.25)
			(keepout
				(tracks allowed)
				(vias not_allowed)
				(pads allowed)
				(copperpour not_allowed)
				(footprints allowed)
			)
			(placement
				(enabled no)
				(sheetname "")
			)
			(fill
				(thermal_gap 0.5)
				(thermal_bridge_width 0.5)
				(island_removal_mode 0)
			)
			(polygon
				(pts
					(xy 399.970498 -33.830006) (xy 399.970498 -34.338006) (xy 400.732498 -34.338006) (xy 400.732498 -33.830006)
				)
			)
		)
		(zone
			(layer "B.Cu")
			(hatch none 0.5)
			(connect_pads
				(clearance 0)
			)
			(min_thickness 0.25)
			(keepout
				(tracks not_allowed)
				(vias allowed)
				(pads allowed)
				(copperpour not_allowed)
				(footprints allowed)
			)
			(placement
				(enabled no)
				(sheetname "")
			)
			(fill
				(thermal_gap 0.5)
				(thermal_bridge_width 0.5)
				(island_removal_mode 0)
			)
			(polygon
				(pts
					(xy 400.732498 -33.830006) (xy 400.732498 -34.338006) (xy 399.970498 -34.338006) (xy 399.970498 -33.830006)
				)
			)
		)
	)
	(footprint ""
		(layer "B.Cu")
		(at 390.4742 -61.7728 180)
		(property "Reference" "U2T3"
			(at 5.31368 1.00711 180)
			(unlocked yes)
			(layer "B.SilkS")
			(effects
				(font
					(size 0.7874 0.5842)
					(thickness 0.1524)
				)
				(justify left mirror)
			)
		)
		(property "Value" ""
			(at 0 0 0)
			(layer "B.Fab")
			(effects
				(font
					(size 1.27 1.27)
				)
				(justify mirror)
			)
		)
		(duplicate_pad_numbers_are_jumpers no)
		(fp_circle
			(center 0.4699 -0.8382)
			(end 0.3429 -0.8382)
			(stroke
				(width 0.254)
				(type default)
			)
			(fill no)
			(layer "B.SilkS")
		)
		(fp_poly
			(pts
				(xy -0.21463 -0.450088) (xy -1.56337 -0.450088) (xy -1.56337 1.75006) (xy -0.21463 1.75006)
			)
			(stroke
				(width 0)
				(type default)
			)
			(fill no)
			(layer "B.CrtYd")
		)
		(fp_line
			(start -0.21463 1.75006)
			(end -0.21463 -0.450088)
			(stroke
				(width 0.1)
				(type default)
			)
			(layer "B.Fab")
		)
		(fp_line
			(start -0.21463 -0.450088)
			(end -1.56337 -0.450088)
			(stroke
				(width 0.1)
				(type default)
			)
			(layer "B.Fab")
		)
		(fp_line
			(start -1.56337 1.75006)
			(end -0.21463 1.75006)
			(stroke
				(width 0.1)
				(type default)
			)
			(layer "B.Fab")
		)
		(fp_line
			(start -1.56337 -0.450088)
			(end -1.56337 1.75006)
			(stroke
				(width 0.1)
				(type default)
			)
			(layer "B.Fab")
		)
		(fp_circle
			(center 0.4699 -0.8382)
			(end 0.3429 -0.8382)
			(stroke
				(width 0.254)
				(type default)
			)
			(fill no)
			(layer "B.Fab")
		)
		(pad "1" smd rect
			(at 0 0)
			(size 1.016 0.381)
			(layers "B.Cu" "B.Mask" "B.Paste")
			(net "FM_DUAL_BIOS_SEL_N")
		)
		(pad "2" smd rect
			(at 0 0.649986)
			(size 1.016 0.381)
			(layers "B.Cu" "B.Mask" "B.Paste")
			(net "SPI_SWITCH_CS0_N")
		)
		(pad "3" smd rect
			(at 0 1.299972)
			(size 1.016 0.381)
			(layers "B.Cu" "B.Mask" "B.Paste")
			(net "GND")
		)
		(pad "4" smd rect
			(at -1.778 1.299972)
			(size 1.016 0.381)
			(layers "B.Cu" "B.Mask" "B.Paste")
			(net "SPI_CS0_PRIMARY_N")
		)
		(pad "5" smd rect
			(at -1.778 0)
			(size 1.016 0.381)
			(layers "B.Cu" "B.Mask" "B.Paste")
			(net "P3V3_STBY")
		)
	)
	(footprint ""
		(layer "B.Cu")
		(at 390.13765 -107.85475)
		(property "Reference" "C2N12"
			(at 0 0 0)
			(layer "B.SilkS")
			(hide yes)
			(effects
				(font
					(size 1.27 1.27)
				)
				(justify mirror)
			)
		)
		(property "Value" ""
			(at 0 0 0)
			(layer "B.Fab")
			(effects
				(font
					(size 1.27 1.27)
				)
				(justify mirror)
			)
		)
		(duplicate_pad_numbers_are_jumpers no)
		(fp_rect
			(start 0.2794 0.9144)
			(end -0.2794 -0.1143)
			(stroke
				(width 0)
				(type default)
			)
			(fill no)
			(layer "B.CrtYd")
		)
		(fp_line
			(start -0.2794 -0.1143)
			(end -0.2794 0.9144)
			(stroke
				(width 0.1)
				(type default)
			)
			(layer "B.Fab")
		)
		(fp_line
			(start -0.2794 0.9144)
			(end 0.2794 0.9144)
			(stroke
				(width 0.1)
				(type default)
			)
			(layer "B.Fab")
		)
		(fp_line
			(start 0.2794 -0.1143)
			(end -0.2794 -0.1143)
			(stroke
				(width 0.1)
				(type default)
			)
			(layer "B.Fab")
		)
		(fp_line
			(start 0.2794 0.9144)
			(end 0.2794 -0.1143)
			(stroke
				(width 0.1)
				(type default)
			)
			(layer "B.Fab")
		)
		(pad "1" smd custom
			(at 0 0 270)
			(size 0.10414 0.10414)
			(layers "B.Cu" "B.Mask" "B.Paste")
			(net "PVNN_PCH_STBY")
			(options
				(clearance outline)
				(anchor circle)
			)
			(primitives
				(gr_poly
					(pts
						(xy -0.20828 -0.08636) (xy -0.20828 0.08636) (xy -0.08636 0.20828) (xy 0.086614 0.20828) (xy 0.20828 0.086614)
						(xy 0.20828 -0.08636) (xy 0.08636 -0.20828) (xy -0.08636 -0.20828)
					)
					(width 0)
					(fill yes)
				)
			)
		)
		(pad "2" smd custom
			(at 0 0.8001 270)
			(size 0.10414 0.10414)
			(layers "B.Cu" "B.Mask" "B.Paste")
			(net "GND")
			(options
				(clearance outline)
				(anchor circle)
			)
			(primitives
				(gr_poly
					(pts
						(xy -0.20828 -0.08636) (xy -0.20828 0.08636) (xy -0.08636 0.20828) (xy 0.086614 0.20828) (xy 0.20828 0.086614)
						(xy 0.20828 -0.08636) (xy 0.08636 -0.20828) (xy -0.08636 -0.20828)
					)
					(width 0)
					(fill yes)
				)
			)
		)
		(zone
			(layer "B.Cu")
			(hatch none 0.5)
			(connect_pads
				(clearance 0)
			)
			(min_thickness 0.25)
			(keepout
				(tracks not_allowed)
				(vias allowed)
				(pads allowed)
				(copperpour not_allowed)
				(footprints allowed)
			)
			(placement
				(enabled no)
				(sheetname "")
			)
			(fill
				(thermal_gap 0.5)
				(thermal_bridge_width 0.5)
				(island_removal_mode 0)
			)
			(polygon
				(pts
					(xy 390.22528 -107.6452) (xy 390.22528 -107.2642) (xy 390.05002 -107.2642) (xy 390.049766 -107.6452)
				)
			)
		)
		(zone
			(layer "B.Cu")
			(hatch none 0.5)
			(connect_pads
				(clearance 0)
			)
			(min_thickness 0.25)
			(keepout
				(tracks allowed)
				(vias not_allowed)
				(pads allowed)
				(copperpour not_allowed)
				(footprints allowed)
			)
			(placement
				(enabled no)
				(sheetname "")
			)
			(fill
				(thermal_gap 0.5)
				(thermal_bridge_width 0.5)
				(island_removal_mode 0)
			)
			(polygon
				(pts
					(xy 390.22528 -107.6452) (xy 390.22528 -107.2642) (xy 390.05002 -107.2642) (xy 390.049766 -107.6452)
				)
			)
		)
	)
	(footprint ""
		(layer "B.Cu")
		(at 433.578 -152.4 -90)
		(property "Reference" "R2L12"
			(at 0 0 90)
			(layer "B.SilkS")
			(hide yes)
			(effects
				(font
					(size 1.27 1.27)
				)
				(justify mirror)
			)
		)
		(property "Value" ""
			(at 0 0 90)
			(layer "B.Fab")
			(effects
				(font
					(size 1.27 1.27)
				)
				(justify mirror)
			)
		)
		(duplicate_pad_numbers_are_jumpers no)
		(fp_poly
			(pts
				(xy 0.2794 -0.1016) (xy -0.2794 -0.1016) (xy -0.2794 0.9906) (xy 0.2794 0.9906)
			)
			(stroke
				(width 0)
				(type default)
			)
			(fill no)
			(layer "B.CrtYd")
		)
		(fp_line
			(start -0.2794 0.9906)
			(end -0.2794 -0.1016)
			(stroke
				(width 0.1)
				(type default)
			)
			(layer "B.Fab")
		)
		(fp_line
			(start 0.2794 0.9906)
			(end -0.2794 0.9906)
			(stroke
				(width 0.1)
				(type default)
			)
			(layer "B.Fab")
		)
		(fp_line
			(start -0.2794 -0.1016)
			(end 0.2794 -0.1016)
			(stroke
				(width 0.1)
				(type default)
			)
			(layer "B.Fab")
		)
		(fp_line
			(start 0.2794 -0.1016)
			(end 0.2794 0.9906)
			(stroke
				(width 0.1)
				(type default)
			)
			(layer "B.Fab")
		)
		(pad "1" smd rect
			(at 0 0 90)
			(size 0.508 0.508)
			(layers "B.Cu" "B.Mask" "B.Paste")
			(net "P3V3_STBY")
		)
		(pad "2" smd rect
			(at 0 0.889 90)
			(size 0.508 0.508)
			(layers "B.Cu" "B.Mask" "B.Paste")
			(net "SGPIO_PCH_SATA_LOAD_R")
		)
		(zone
			(layer "B.Cu")
			(hatch none 0.5)
			(connect_pads
				(clearance 0)
			)
			(min_thickness 0.25)
			(keepout
				(tracks not_allowed)
				(vias allowed)
				(pads allowed)
				(copperpour not_allowed)
				(footprints allowed)
			)
			(placement
				(enabled no)
				(sheetname "")
			)
			(fill
				(thermal_gap 0.5)
				(thermal_bridge_width 0.5)
				(island_removal_mode 0)
			)
			(polygon
				(pts
					(xy 432.943 -152.146) (xy 432.943 -152.654) (xy 433.324 -152.654) (xy 433.324 -152.146)
				)
			)
		)
		(zone
			(layer "B.Cu")
			(hatch none 0.5)
			(connect_pads
				(clearance 0)
			)
			(min_thickness 0.25)
			(keepout
				(tracks allowed)
				(vias not_allowed)
				(pads allowed)
				(copperpour not_allowed)
				(footprints allowed)
			)
			(placement
				(enabled no)
				(sheetname "")
			)
			(fill
				(thermal_gap 0.5)
				(thermal_bridge_width 0.5)
				(island_removal_mode 0)
			)
			(polygon
				(pts
					(xy 433.324 -152.146) (xy 433.324 -152.654) (xy 432.943 -152.654) (xy 432.943 -152.146)
				)
			)
		)
	)
	(footprint ""
		(layer "B.Cu")
		(at 22.606 -75.946 90)
		(property "Reference" "C9P14"
			(at 0 0 90)
			(layer "B.SilkS")
			(hide yes)
			(effects
				(font
					(size 1.27 1.27)
				)
				(justify mirror)
			)
		)
		(property "Value" ""
			(at 0 0 90)
			(layer "B.Fab")
			(effects
				(font
					(size 1.27 1.27)
				)
				(justify mirror)
			)
		)
		(duplicate_pad_numbers_are_jumpers no)
		(fp_rect
			(start 0.4953 1.6002)
			(end -0.4953 -0.2032)
			(stroke
				(width 0)
				(type default)
			)
			(fill no)
			(layer "B.CrtYd")
		)
		(fp_line
			(start 0.4953 -0.2032)
			(end -0.4953 -0.2032)
			(stroke
				(width 0.1)
				(type default)
			)
			(layer "B.Fab")
		)
		(fp_line
			(start -0.4953 -0.2032)
			(end -0.4953 1.6002)
			(stroke
				(width 0.1)
				(type default)
			)
			(layer "B.Fab")
		)
		(fp_line
			(start 0.4953 1.6002)
			(end 0.4953 -0.2032)
			(stroke
				(width 0.1)
				(type default)
			)
			(layer "B.Fab")
		)
		(fp_line
			(start -0.4953 1.6002)
			(end 0.4953 1.6002)
			(stroke
				(width 0.1)
				(type default)
			)
			(layer "B.Fab")
		)
		(pad "1" smd rect
			(at 0 0 270)
			(size 0.762 0.889)
			(layers "B.Cu" "B.Mask" "B.Paste")
			(net "A_HSC_TIMER")
		)
		(pad "2" smd rect
			(at 0 1.397 270)
			(size 0.762 0.889)
			(layers "B.Cu" "B.Mask" "B.Paste")
			(net "AGND_HSC")
		)
		(zone
			(layer "B.Cu")
			(hatch none 0.5)
			(connect_pads
				(clearance 0)
			)
			(min_thickness 0.25)
			(keepout
				(tracks not_allowed)
				(vias allowed)
				(pads allowed)
				(copperpour not_allowed)
				(footprints allowed)
			)
			(placement
				(enabled no)
				(sheetname "")
			)
			(fill
				(thermal_gap 0.5)
				(thermal_bridge_width 0.5)
				(island_removal_mode 0)
			)
			(polygon
				(pts
					(xy 23.5585 -76.327) (xy 23.0505 -76.327) (xy 23.0505 -75.565) (xy 23.5585 -75.565)
				)
			)
		)
	)
	(footprint ""
		(layer "B.Cu")
		(at 193.092832 -8.122412 -90)
		(property "Reference" "C6U10"
			(at 0 0 90)
			(layer "B.SilkS")
			(hide yes)
			(effects
				(font
					(size 1.27 1.27)
				)
				(justify mirror)
			)
		)
		(property "Value" ""
			(at 0 0 90)
			(layer "B.Fab")
			(effects
				(font
					(size 1.27 1.27)
				)
				(justify mirror)
			)
		)
		(duplicate_pad_numbers_are_jumpers no)
		(fp_rect
			(start 0.7239 1.9939)
			(end -0.7239 -0.2159)
			(stroke
				(width 0)
				(type default)
			)
			(fill no)
			(layer "B.CrtYd")
		)
		(fp_line
			(start -0.7239 1.9939)
			(end -0.7239 -0.2159)
			(stroke
				(width 0.1)
				(type default)
			)
			(layer "B.Fab")
		)
		(fp_line
			(start 0.7239 1.9939)
			(end -0.7239 1.9939)
			(stroke
				(width 0.1)
				(type default)
			)
			(layer "B.Fab")
		)
		(fp_line
			(start -0.7239 -0.2159)
			(end 0.7239 -0.2159)
			(stroke
				(width 0.1)
				(type default)
			)
			(layer "B.Fab")
		)
		(fp_line
			(start 0.7239 -0.2159)
			(end 0.7239 1.9939)
			(stroke
				(width 0.1)
				(type default)
			)
			(layer "B.Fab")
		)
		(pad "1" smd rect
			(at 0 0 90)
			(size 1.27 1.016)
			(layers "B.Cu" "B.Mask" "B.Paste")
			(net "P12V_NVDIMM_ABC")
		)
		(pad "2" smd rect
			(at 0 1.778 90)
			(size 1.27 1.016)
			(layers "B.Cu" "B.Mask" "B.Paste")
			(net "GND")
		)
		(zone
			(layer "B.Cu")
			(hatch none 0.5)
			(connect_pads
				(clearance 0)
			)
			(min_thickness 0.25)
			(keepout
				(tracks not_allowed)
				(vias allowed)
				(pads allowed)
				(copperpour not_allowed)
				(footprints allowed)
			)
			(placement
				(enabled no)
				(sheetname "")
			)
			(fill
				(thermal_gap 0.5)
				(thermal_bridge_width 0.5)
				(island_removal_mode 0)
			)
			(polygon
				(pts
					(xy 191.822832 -7.487412) (xy 192.584832 -7.487412) (xy 192.584832 -8.757412) (xy 191.822832 -8.757412)
				)
			)
		)
	)
	(footprint ""
		(layer "B.Cu")
		(at 474.814138 -127.242316 -90)
		(property "Reference" "R1W34"
			(at 0.8382 -0.67818 270)
			(unlocked yes)
			(layer "B.SilkS")
			(effects
				(font
					(size 0.4064 0.254)
					(thickness 0.1524)
				)
				(justify left mirror)
			)
		)
		(property "Value" ""
			(at 0 0 90)
			(layer "B.Fab")
			(effects
				(font
					(size 1.27 1.27)
				)
				(justify mirror)
			)
		)
		(duplicate_pad_numbers_are_jumpers no)
		(fp_poly
			(pts
				(xy 0.2794 -0.1016) (xy -0.2794 -0.1016) (xy -0.2794 0.9906) (xy 0.2794 0.9906)
			)
			(stroke
				(width 0)
				(type default)
			)
			(fill no)
			(layer "B.CrtYd")
		)
		(fp_line
			(start -0.2794 0.9906)
			(end -0.2794 -0.1016)
			(stroke
				(width 0.1)
				(type default)
			)
			(layer "B.Fab")
		)
		(fp_line
			(start 0.2794 0.9906)
			(end -0.2794 0.9906)
			(stroke
				(width 0.1)
				(type default)
			)
			(layer "B.Fab")
		)
		(fp_line
			(start -0.2794 -0.1016)
			(end 0.2794 -0.1016)
			(stroke
				(width 0.1)
				(type default)
			)
			(layer "B.Fab")
		)
		(fp_line
			(start 0.2794 -0.1016)
			(end 0.2794 0.9906)
			(stroke
				(width 0.1)
				(type default)
			)
			(layer "B.Fab")
		)
		(pad "1" smd rect
			(at 0 0 90)
			(size 0.508 0.508)
			(layers "B.Cu" "B.Mask" "B.Paste")
			(net "SMB_DEBUG_STBY_LVC3_SDA_R1")
		)
		(pad "2" smd rect
			(at 0 0.889 90)
			(size 0.508 0.508)
			(layers "B.Cu" "B.Mask" "B.Paste")
			(net "SMB_DEBUG_STBY_LVC3_SDA")
		)
		(zone
			(layer "B.Cu")
			(hatch none 0.5)
			(connect_pads
				(clearance 0)
			)
			(min_thickness 0.25)
			(keepout
				(tracks not_allowed)
				(vias allowed)
				(pads allowed)
				(copperpour not_allowed)
				(footprints allowed)
			)
			(placement
				(enabled no)
				(sheetname "")
			)
			(fill
				(thermal_gap 0.5)
				(thermal_bridge_width 0.5)
				(island_removal_mode 0)
			)
			(polygon
				(pts
					(xy 474.179138 -126.988316) (xy 474.179138 -127.496316) (xy 474.560138 -127.496316) (xy 474.560138 -126.988316)
				)
			)
		)
		(zone
			(layer "B.Cu")
			(hatch none 0.5)
			(connect_pads
				(clearance 0)
			)
			(min_thickness 0.25)
			(keepout
				(tracks allowed)
				(vias not_allowed)
				(pads allowed)
				(copperpour not_allowed)
				(footprints allowed)
			)
			(placement
				(enabled no)
				(sheetname "")
			)
			(fill
				(thermal_gap 0.5)
				(thermal_bridge_width 0.5)
				(island_removal_mode 0)
			)
			(polygon
				(pts
					(xy 474.560138 -126.988316) (xy 474.560138 -127.496316) (xy 474.179138 -127.496316) (xy 474.179138 -126.988316)
				)
			)
		)
	)
)
